# S9S_MB_2U (Grand Teton) — schematic netlist excerpt (pin names and nets, part order shuffled) for the footprints in the layout excerpt that follows; sources: Cadence DE-HDL packaged netlist, KiCad conversion of 03242023_DA0F0TMBIJ0_F0T_Motherboard_J_brd_V01_OCP.brd

R3198  Q_RES  22 1% CHIP  pkg 0402LF  page 207 : A = CLK_100M_OCP_V3_2_C_R_DP ; B = CLK_100M_OCP_V3_2_C_DP
C1037  Q_CAP  22UF 4V 20% X6S  pkg C0402  page 74 : A = PVCCIN_CPU0 ; B = GND

(kicad_pcb
	(version 20260206)
	(generator "pcbnew")
	(generator_version "10.0")
	(general
		(thickness 1.6)
		(legacy_teardrops no)
	)
	(paper "A4")
	(title_block
		(title "03242023_DA0F0TMBIJ0_F0T_Motherboard_J_brd_V01_OCP.brd")
		(comment 1 "Grand Teton / footprints 3365-3366 of 6105")
	)
	(layers
		(0 "F.Cu" signal "TOP")
		(4 "In1.Cu" signal "GND")
		(6 "In2.Cu" signal "IN1")
		(8 "In3.Cu" signal "GND1")
		(10 "In4.Cu" signal "IN2")
		(12 "In5.Cu" signal "GND2")
		(14 "In6.Cu" signal "IN3")
		(16 "In7.Cu" signal "GND3")
		(18 "In8.Cu" signal "VCC")
		(20 "In9.Cu" signal "VCC1")
		(22 "In10.Cu" signal "GND4")
		(24 "In11.Cu" signal "IN4")
		(26 "In12.Cu" signal "GND5")
		(28 "In13.Cu" signal "IN5")
		(30 "In14.Cu" signal "GND6")
		(32 "In15.Cu" signal "IN6")
		(34 "In16.Cu" signal "GND7")
		(2 "B.Cu" signal "BOTTOM")
		(9 "F.Adhes" user "F.Adhesive")
		(11 "B.Adhes" user "B.Adhesive")
		(13 "F.Paste" user "Package Geometry/Pastemask Top")
		(15 "B.Paste" user "Package Geometry/Pastemask Bottom")
		(5 "F.SilkS" user "Ref Des/Silkscreen Top")
		(7 "B.SilkS" user "Ref Des/Silkscreen Bottom")
		(1 "F.Mask" user "Board Geometry/Soldermask Top")
		(3 "B.Mask" user "Board Geometry/Soldermask Bottom")
		(17 "Dwgs.User" user "User.Drawings")
		(19 "Cmts.User" user "User.Comments")
		(21 "Eco1.User" user "User.Eco1")
		(23 "Eco2.User" user "User.Eco2")
		(25 "Edge.Cuts" user "Board Geometry/Outline")
		(27 "Margin" user)
		(31 "F.CrtYd" user "Package Geometry/Place Bound Top")
		(29 "B.CrtYd" user "Package Geometry/Place Bound Bottom")
		(35 "F.Fab" user "Ref Des/Assembly Top")
		(33 "B.Fab" user "Ref Des/Assembly Bottom")
	)
	(footprint ""
		(layer "F.Cu")
		(at 239.203738 -119.183658 -90)
		(property "Reference" "R3198"
			(at 0 0 270)
			(layer "F.SilkS")
			(hide yes)
			(effects
				(font
					(size 1.27 1.27)
				)
			)
		)
		(property "Value" ""
			(at 0 0 270)
			(layer "F.Fab")
			(effects
				(font
					(size 1.27 1.27)
				)
			)
		)
		(duplicate_pad_numbers_are_jumpers no)
		(fp_line
			(start -0.7874 0.4064)
			(end -0.7874 0.070358)
			(stroke
				(width 0.1524)
				(type default)
			)
			(layer "F.SilkS")
		)
		(fp_line
			(start 0.7874 0.4064)
			(end -0.7874 0.4064)
			(stroke
				(width 0.1524)
				(type default)
			)
			(layer "F.SilkS")
		)
		(fp_line
			(start 0.7874 0.022098)
			(end 0.7874 0.4064)
			(stroke
				(width 0.1524)
				(type default)
			)
			(layer "F.SilkS")
		)
		(fp_line
			(start -0.254762 -0.4064)
			(end 0.385318 -0.4064)
			(stroke
				(width 0.1524)
				(type default)
			)
			(layer "F.SilkS")
		)
		(fp_line
			(start -0.67945 0.3048)
			(end -0.67945 -0.305054)
			(stroke
				(width 0.1)
				(type default)
			)
			(layer "F.Fab")
		)
		(fp_line
			(start -0.12065 0.3048)
			(end -0.67945 0.3048)
			(stroke
				(width 0.1)
				(type default)
			)
			(layer "F.Fab")
		)
		(fp_line
			(start 0.120396 0.3048)
			(end 0.120396 0.2794)
			(stroke
				(width 0.1)
				(type default)
			)
			(layer "F.Fab")
		)
		(fp_line
			(start 0.67945 0.3048)
			(end 0.120396 0.3048)
			(stroke
				(width 0.1)
				(type default)
			)
			(layer "F.Fab")
		)
		(fp_line
			(start -0.12065 0.2794)
			(end -0.12065 0.3048)
			(stroke
				(width 0.1)
				(type default)
			)
			(layer "F.Fab")
		)
		(fp_line
			(start 0.120396 0.2794)
			(end -0.12065 0.2794)
			(stroke
				(width 0.1)
				(type default)
			)
			(layer "F.Fab")
		)
		(fp_line
			(start -0.12065 -0.2794)
			(end 0.12065 -0.2794)
			(stroke
				(width 0.1)
				(type default)
			)
			(layer "F.Fab")
		)
		(fp_line
			(start 0.12065 -0.2794)
			(end 0.12065 -0.3048)
			(stroke
				(width 0.1)
				(type default)
			)
			(layer "F.Fab")
		)
		(fp_line
			(start 0.12065 -0.3048)
			(end 0.67945 -0.3048)
			(stroke
				(width 0.1)
				(type default)
			)
			(layer "F.Fab")
		)
		(fp_line
			(start 0.67945 -0.3048)
			(end 0.67945 0.3048)
			(stroke
				(width 0.1)
				(type default)
			)
			(layer "F.Fab")
		)
		(fp_line
			(start -0.67945 -0.305054)
			(end -0.12065 -0.305054)
			(stroke
				(width 0.1)
				(type default)
			)
			(layer "F.Fab")
		)
		(fp_line
			(start -0.12065 -0.305054)
			(end -0.12065 -0.2794)
			(stroke
				(width 0.1)
				(type default)
			)
			(layer "F.Fab")
		)
		(pad "1" smd circle
			(at -0.40005 0 270)
			(size 0 0)
			(layers "F.Cu" "F.Mask" "F.Paste")
			(net "CLK_100M_OCP_V3_2_C_R_DP")
		)
		(pad "2" smd circle
			(at 0.40005 0 270)
			(size 0 0)
			(layers "F.Cu" "F.Mask" "F.Paste")
			(net "CLK_100M_OCP_V3_2_C_DP")
		)
	)
	(footprint ""
		(layer "F.Cu")
		(at 367.44783 -241.976656 -90)
		(property "Reference" "C1037"
			(at 0 0 270)
			(layer "F.SilkS")
			(hide yes)
			(effects
				(font
					(size 1.27 1.27)
				)
			)
		)
		(property "Value" ""
			(at 0 0 270)
			(layer "F.Fab")
			(effects
				(font
					(size 1.27 1.27)
				)
			)
		)
		(duplicate_pad_numbers_are_jumpers no)
		(fp_line
			(start -0.7874 0.4064)
			(end -0.7874 -0.4064)
			(stroke
				(width 0.1524)
				(type default)
			)
			(layer "F.SilkS")
		)
		(fp_line
			(start 0.7874 0.4064)
			(end -0.7874 0.4064)
			(stroke
				(width 0.1524)
				(type default)
			)
			(layer "F.SilkS")
		)
		(fp_line
			(start -0.7874 -0.4064)
			(end 0.7874 -0.4064)
			(stroke
				(width 0.1524)
				(type default)
			)
			(layer "F.SilkS")
		)
		(fp_line
			(start 0.7874 -0.4064)
			(end 0.7874 0.4064)
			(stroke
				(width 0.1524)
				(type default)
			)
			(layer "F.SilkS")
		)
		(fp_line
			(start -0.67945 0.3048)
			(end -0.67945 -0.305054)
			(stroke
				(width 0.1)
				(type default)
			)
			(layer "F.Fab")
		)
		(fp_line
			(start -0.12065 0.3048)
			(end -0.67945 0.3048)
			(stroke
				(width 0.1)
				(type default)
			)
			(layer "F.Fab")
		)
		(fp_line
			(start 0.120396 0.3048)
			(end 0.120396 0.2794)
			(stroke
				(width 0.1)
				(type default)
			)
			(layer "F.Fab")
		)
		(fp_line
			(start 0.67945 0.3048)
			(end 0.120396 0.3048)
			(stroke
				(width 0.1)
				(type default)
			)
			(layer "F.Fab")
		)
		(fp_line
			(start -0.12065 0.2794)
			(end -0.12065 0.3048)
			(stroke
				(width 0.1)
				(type default)
			)
			(layer "F.Fab")
		)
		(fp_line
			(start 0.120396 0.2794)
			(end -0.12065 0.2794)
			(stroke
				(width 0.1)
				(type default)
			)
			(layer "F.Fab")
		)
		(fp_line
			(start -0.12065 -0.2794)
			(end 0.12065 -0.2794)
			(stroke
				(width 0.1)
				(type default)
			)
			(layer "F.Fab")
		)
		(fp_line
			(start 0.12065 -0.2794)
			(end 0.12065 -0.3048)
			(stroke
				(width 0.1)
				(type default)
			)
			(layer "F.Fab")
		)
		(fp_line
			(start 0.12065 -0.3048)
			(end 0.67945 -0.3048)
			(stroke
				(width 0.1)
				(type default)
			)
			(layer "F.Fab")
		)
		(fp_line
			(start 0.67945 -0.3048)
			(end 0.67945 0.3048)
			(stroke
				(width 0.1)
				(type default)
			)
			(layer "F.Fab")
		)
		(fp_line
			(start -0.67945 -0.305054)
			(end -0.12065 -0.305054)
			(stroke
				(width 0.1)
				(type default)
			)
			(layer "F.Fab")
		)
		(fp_line
			(start -0.12065 -0.305054)
			(end -0.12065 -0.2794)
			(stroke
				(width 0.1)
				(type default)
			)
			(layer "F.Fab")
		)
		(pad "1" smd circle
			(at -0.40005 0 270)
			(size 0 0)
			(layers "F.Cu" "F.Mask" "F.Paste")
			(net "PVCCIN_CPU0")
		)
		(pad "2" smd circle
			(at 0.40005 0 270)
			(size 0 0)
			(layers "F.Cu" "F.Mask" "F.Paste")
			(net "GND")
		)
	)
)
